(kicad_pcb
	(version 20260206)
	(generator "pcbnew")
	(generator_version "10.0")
	(general
		(thickness 1.6)
		(legacy_teardrops no)
	)
	(paper "A4")
	(title_block
		(title "Wiwynn_Tioga_Pass_MB.brd")
		(comment 1 "Tioga Pass / footprint 3922 of 4770 (EU3P1), pads 1-41 of 41")
	)
	(layers
		(0 "F.Cu" signal "TOP")
		(4 "In1.Cu" signal "L2GND")
		(6 "In2.Cu" signal "L3")
		(8 "In3.Cu" signal "L4GND")
		(10 "In4.Cu" signal "L5")
		(12 "In5.Cu" signal "L6GND")
		(14 "In6.Cu" signal "L7VCC")
		(16 "In7.Cu" signal "L8VCC")
		(18 "In8.Cu" signal "L9GND")
		(20 "In9.Cu" signal "L10")
		(22 "In10.Cu" signal "L11GND")
		(24 "In11.Cu" signal "L12")
		(26 "In12.Cu" signal "L13GND")
		(2 "B.Cu" signal "BOTTOM")
		(9 "F.Adhes" user "F.Adhesive")
		(11 "B.Adhes" user "B.Adhesive")
		(13 "F.Paste" user "Package Geometry/Pastemask Top")
		(15 "B.Paste" user "Package Geometry/Pastemask Bottom")
		(5 "F.SilkS" user "Ref Des/Silkscreen Top")
		(7 "B.SilkS" user "Ref Des/Silkscreen Bottom")
		(1 "F.Mask" user "Board Geometry/Soldermask Top")
		(3 "B.Mask" user "Board Geometry/Soldermask Bottom")
		(17 "Dwgs.User" user "User.Drawings")
		(19 "Cmts.User" user "User.Comments")
		(21 "Eco1.User" user "User.Eco1")
		(23 "Eco2.User" user "User.Eco2")
		(25 "Edge.Cuts" user "Board Geometry/Outline")
		(27 "Margin" user)
		(31 "F.CrtYd" user "Package Geometry/Place Bound Top")
		(29 "B.CrtYd" user "Package Geometry/Place Bound Bottom")
		(35 "F.Fab" user "Ref Des/Assembly Top")
		(33 "B.Fab" user "Ref Des/Assembly Bottom")
	)
	(footprint ""
		(layer "B.Cu")
		(at 346.5322 -87.4522 -90)
		(property "Reference" "EU3P1"
			(at -1.80975 3.2893 0)
			(unlocked yes)
			(layer "B.SilkS")
			(effects
				(font
					(size 0.7874 0.5842)
					(thickness 0.1524)
				)
				(justify left mirror)
			)
		)
		(property "Value" ""
			(at 0 0 90)
			(layer "B.Fab")
			(effects
				(font
					(size 1.27 1.27)
				)
				(justify mirror)
			)
		)
		(duplicate_pad_numbers_are_jumpers no)
		(pad "1" smd custom
			(at 2.4511 -1.800098 90)
			(size 0.0508 0.0508)
			(layers "B.Cu" "B.Mask" "B.Paste")
			(net "Net_331")
			(options
				(clearance outline)
				(anchor circle)
			)
			(primitives
				(gr_poly
					(pts
						(arc
							(start 0.254 0.1016)
							(mid 0.3556 0)
							(end 0.254 -0.1016)
						)
						(xy -0.3556 -0.1016) (xy -0.3556 0.1016)
					)
					(width 0)
					(fill yes)
				)
			)
		)
		(pad "2" smd custom
			(at 2.4511 -1.400048 90)
			(size 0.0508 0.0508)
			(layers "B.Cu" "B.Mask" "B.Paste")
			(net "Net_332")
			(options
				(clearance outline)
				(anchor circle)
			)
			(primitives
				(gr_poly
					(pts
						(arc
							(start 0.254 0.1016)
							(mid 0.3556 0)
							(end 0.254 -0.1016)
						)
						(xy -0.3556 -0.1016) (xy -0.3556 0.1016)
					)
					(width 0)
					(fill yes)
				)
			)
		)
		(pad "3" smd custom
			(at 2.4511 -0.999998 90)
			(size 0.0508 0.0508)
			(layers "B.Cu" "B.Mask" "B.Paste")
			(net "Net_269")
			(options
				(clearance outline)
				(anchor circle)
			)
			(primitives
				(gr_poly
					(pts
						(arc
							(start 0.254 0.1016)
							(mid 0.3556 0)
							(end 0.254 -0.1016)
						)
						(xy -0.3556 -0.1016) (xy -0.3556 0.1016)
					)
					(width 0)
					(fill yes)
				)
			)
		)
		(pad "4" smd custom
			(at 2.4511 -0.599948 90)
			(size 0.0508 0.0508)
			(layers "B.Cu" "B.Mask" "B.Paste")
			(net "Net_333")
			(options
				(clearance outline)
				(anchor circle)
			)
			(primitives
				(gr_poly
					(pts
						(arc
							(start 0.254 0.1016)
							(mid 0.3556 0)
							(end 0.254 -0.1016)
						)
						(xy -0.3556 -0.1016) (xy -0.3556 0.1016)
					)
					(width 0)
					(fill yes)
				)
			)
		)
		(pad "5" smd custom
			(at 2.4511 -0.199898 90)
			(size 0.0508 0.0508)
			(layers "B.Cu" "B.Mask" "B.Paste")
			(net "VR_PVCCIO_CPU0_PWM1")
			(options
				(clearance outline)
				(anchor circle)
			)
			(primitives
				(gr_poly
					(pts
						(arc
							(start 0.254 0.1016)
							(mid 0.3556 0)
							(end 0.254 -0.1016)
						)
						(xy -0.3556 -0.1016) (xy -0.3556 0.1016)
					)
					(width 0)
					(fill yes)
				)
			)
		)
		(pad "6" smd custom
			(at 2.4511 0.199898 90)
			(size 0.0508 0.0508)
			(layers "B.Cu" "B.Mask" "B.Paste")
			(net "SMB_VR_STBY_LVC3_SDA")
			(options
				(clearance outline)
				(anchor circle)
			)
			(primitives
				(gr_poly
					(pts
						(arc
							(start 0.254 0.1016)
							(mid 0.3556 0)
							(end 0.254 -0.1016)
						)
						(xy -0.3556 -0.1016) (xy -0.3556 0.1016)
					)
					(width 0)
					(fill yes)
				)
			)
		)
		(pad "7" smd custom
			(at 2.4511 0.599948 90)
			(size 0.0508 0.0508)
			(layers "B.Cu" "B.Mask" "B.Paste")
			(net "SMB_VR_STBY_LVC3_SCL")
			(options
				(clearance outline)
				(anchor circle)
			)
			(primitives
				(gr_poly
					(pts
						(arc
							(start 0.254 0.1016)
							(mid 0.3556 0)
							(end 0.254 -0.1016)
						)
						(xy -0.3556 -0.1016) (xy -0.3556 0.1016)
					)
					(width 0)
					(fill yes)
				)
			)
		)
		(pad "8" smd custom
			(at 2.4511 0.999998 90)
			(size 0.0508 0.0508)
			(layers "B.Cu" "B.Mask" "B.Paste")
			(net "Net_270")
			(options
				(clearance outline)
				(anchor circle)
			)
			(primitives
				(gr_poly
					(pts
						(arc
							(start 0.254 0.1016)
							(mid 0.3556 0)
							(end 0.254 -0.1016)
						)
						(xy -0.3556 -0.1016) (xy -0.3556 0.1016)
					)
					(width 0)
					(fill yes)
				)
			)
		)
		(pad "9" smd custom
			(at 2.4511 1.400048 90)
			(size 0.0508 0.0508)
			(layers "B.Cu" "B.Mask" "B.Paste")
			(net "PWRGD_PVCCIO_CPU0_R")
			(options
				(clearance outline)
				(anchor circle)
			)
			(primitives
				(gr_poly
					(pts
						(arc
							(start 0.254 0.1016)
							(mid 0.3556 0)
							(end 0.254 -0.1016)
						)
						(xy -0.3556 -0.1016) (xy -0.3556 0.1016)
					)
					(width 0)
					(fill yes)
				)
			)
		)
		(pad "10" smd custom
			(at 2.4511 1.800098 90)
			(size 0.0508 0.0508)
			(layers "B.Cu" "B.Mask" "B.Paste")
			(net "VR_PVCCIO_CPU0_EN")
			(options
				(clearance outline)
				(anchor circle)
			)
			(primitives
				(gr_poly
					(pts
						(arc
							(start 0.254 0.1016)
							(mid 0.3556 0)
							(end 0.254 -0.1016)
						)
						(xy -0.3556 -0.1016) (xy -0.3556 0.1016)
					)
					(width 0)
					(fill yes)
				)
			)
		)
		(pad "11" smd custom
			(at 1.800098 2.4511 90)
			(size 0.0508 0.0508)
			(layers "B.Cu" "B.Mask" "B.Paste")
			(net "IRQ_PVCCIO_CPU0_VRHOT_N")
			(options
				(clearance outline)
				(anchor circle)
			)
			(primitives
				(gr_poly
					(pts
						(arc
							(start -0.1016 0.254)
							(mid 0 0.3556)
							(end 0.1016 0.254)
						)
						(xy 0.1016 -0.3556) (xy -0.1016 -0.3556)
					)
					(width 0)
					(fill yes)
				)
			)
		)
		(pad "12" smd custom
			(at 1.400048 2.4511 90)
			(size 0.0508 0.0508)
			(layers "B.Cu" "B.Mask" "B.Paste")
			(net "Net_257")
			(options
				(clearance outline)
				(anchor circle)
			)
			(primitives
				(gr_poly
					(pts
						(arc
							(start -0.1016 0.254)
							(mid 0 0.3556)
							(end 0.1016 0.254)
						)
						(xy 0.1016 -0.3556) (xy -0.1016 -0.3556)
					)
					(width 0)
					(fill yes)
				)
			)
		)
		(pad "13" smd custom
			(at 0.999998 2.4511 90)
			(size 0.0508 0.0508)
			(layers "B.Cu" "B.Mask" "B.Paste")
			(net "Net_255")
			(options
				(clearance outline)
				(anchor circle)
			)
			(primitives
				(gr_poly
					(pts
						(arc
							(start -0.1016 0.254)
							(mid 0 0.3556)
							(end 0.1016 0.254)
						)
						(xy 0.1016 -0.3556) (xy -0.1016 -0.3556)
					)
					(width 0)
					(fill yes)
				)
			)
		)
		(pad "14" smd custom
			(at 0.599948 2.4511 90)
			(size 0.0508 0.0508)
			(layers "B.Cu" "B.Mask" "B.Paste")
			(net "Net_256")
			(options
				(clearance outline)
				(anchor circle)
			)
			(primitives
				(gr_poly
					(pts
						(arc
							(start -0.1016 0.254)
							(mid 0 0.3556)
							(end 0.1016 0.254)
						)
						(xy 0.1016 -0.3556) (xy -0.1016 -0.3556)
					)
					(width 0)
					(fill yes)
				)
			)
		)
		(pad "15" smd custom
			(at 0.199898 2.4511 90)
			(size 0.0508 0.0508)
			(layers "B.Cu" "B.Mask" "B.Paste")
			(net "SVID_CLK_PVCCIO_CPU0")
			(options
				(clearance outline)
				(anchor circle)
			)
			(primitives
				(gr_poly
					(pts
						(arc
							(start -0.1016 0.254)
							(mid 0 0.3556)
							(end 0.1016 0.254)
						)
						(xy 0.1016 -0.3556) (xy -0.1016 -0.3556)
					)
					(width 0)
					(fill yes)
				)
			)
		)
		(pad "16" smd custom
			(at -0.199898 2.4511 90)
			(size 0.0508 0.0508)
			(layers "B.Cu" "B.Mask" "B.Paste")
			(net "SVID_VDIO_PVCCIO_CPU0")
			(options
				(clearance outline)
				(anchor circle)
			)
			(primitives
				(gr_poly
					(pts
						(arc
							(start -0.1016 0.254)
							(mid 0 0.3556)
							(end 0.1016 0.254)
						)
						(xy 0.1016 -0.3556) (xy -0.1016 -0.3556)
					)
					(width 0)
					(fill yes)
				)
			)
		)
		(pad "17" smd custom
			(at -0.599948 2.4511 90)
			(size 0.0508 0.0508)
			(layers "B.Cu" "B.Mask" "B.Paste")
			(net "SVID_ALERT_PVCCIO_CPU0")
			(options
				(clearance outline)
				(anchor circle)
			)
			(primitives
				(gr_poly
					(pts
						(arc
							(start -0.1016 0.254)
							(mid 0 0.3556)
							(end 0.1016 0.254)
						)
						(xy 0.1016 -0.3556) (xy -0.1016 -0.3556)
					)
					(width 0)
					(fill yes)
				)
			)
		)
		(pad "18" smd custom
			(at -0.999998 2.4511 90)
			(size 0.0508 0.0508)
			(layers "B.Cu" "B.Mask" "B.Paste")
			(net "Net_300")
			(options
				(clearance outline)
				(anchor circle)
			)
			(primitives
				(gr_poly
					(pts
						(arc
							(start -0.1016 0.254)
							(mid 0 0.3556)
							(end 0.1016 0.254)
						)
						(xy 0.1016 -0.3556) (xy -0.1016 -0.3556)
					)
					(width 0)
					(fill yes)
				)
			)
		)
		(pad "19" smd custom
			(at -1.400048 2.4511 90)
			(size 0.0508 0.0508)
			(layers "B.Cu" "B.Mask" "B.Paste")
			(net "VR_PVCCIO_CPU0_AVSP")
			(options
				(clearance outline)
				(anchor circle)
			)
			(primitives
				(gr_poly
					(pts
						(arc
							(start -0.1016 0.254)
							(mid 0 0.3556)
							(end 0.1016 0.254)
						)
						(xy 0.1016 -0.3556) (xy -0.1016 -0.3556)
					)
					(width 0)
					(fill yes)
				)
			)
		)
		(pad "20" smd custom
			(at -1.800098 2.4511 90)
			(size 0.0508 0.0508)
			(layers "B.Cu" "B.Mask" "B.Paste")
			(net "VSENSE_PVCCIO_CPU0_AVSN")
			(options
				(clearance outline)
				(anchor circle)
			)
			(primitives
				(gr_poly
					(pts
						(arc
							(start -0.1016 0.254)
							(mid 0 0.3556)
							(end 0.1016 0.254)
						)
						(xy 0.1016 -0.3556) (xy -0.1016 -0.3556)
					)
					(width 0)
					(fill yes)
				)
			)
		)
		(pad "21" smd custom
			(at -2.4511 1.800098 90)
			(size 0.0508 0.0508)
			(layers "B.Cu" "B.Mask" "B.Paste")
			(net "VR_PVCCIO_CPU0_AIREF1")
			(options
				(clearance outline)
				(anchor circle)
			)
			(primitives
				(gr_poly
					(pts
						(arc
							(start -0.254 -0.1016)
							(mid -0.3556 0)
							(end -0.254 0.1016)
						)
						(xy 0.3556 0.1016) (xy 0.3556 -0.1016)
					)
					(width 0)
					(fill yes)
				)
			)
		)
		(pad "22" smd custom
			(at -2.4511 1.400048 90)
			(size 0.0508 0.0508)
			(layers "B.Cu" "B.Mask" "B.Paste")
			(net "ISENSE_PVCCIO_CPU0_PH1_IMON")
			(options
				(clearance outline)
				(anchor circle)
			)
			(primitives
				(gr_poly
					(pts
						(arc
							(start -0.254 -0.1016)
							(mid -0.3556 0)
							(end -0.254 0.1016)
						)
						(xy 0.3556 0.1016) (xy 0.3556 -0.1016)
					)
					(width 0)
					(fill yes)
				)
			)
		)
		(pad "23" smd custom
			(at -2.4511 0.999998 90)
			(size 0.0508 0.0508)
			(layers "B.Cu" "B.Mask" "B.Paste")
			(net "GND")
			(options
				(clearance outline)
				(anchor circle)
			)
			(primitives
				(gr_poly
					(pts
						(arc
							(start -0.254 -0.1016)
							(mid -0.3556 0)
							(end -0.254 0.1016)
						)
						(xy 0.3556 0.1016) (xy 0.3556 -0.1016)
					)
					(width 0)
					(fill yes)
				)
			)
		)
		(pad "24" smd custom
			(at -2.4511 0.599948 90)
			(size 0.0508 0.0508)
			(layers "B.Cu" "B.Mask" "B.Paste")
			(net "Net_334")
			(options
				(clearance outline)
				(anchor circle)
			)
			(primitives
				(gr_poly
					(pts
						(arc
							(start -0.254 -0.1016)
							(mid -0.3556 0)
							(end -0.254 0.1016)
						)
						(xy 0.3556 0.1016) (xy 0.3556 -0.1016)
					)
					(width 0)
					(fill yes)
				)
			)
		)
		(pad "25" smd custom
			(at -2.4511 0.199898 90)
			(size 0.0508 0.0508)
			(layers "B.Cu" "B.Mask" "B.Paste")
			(net "Net_251")
			(options
				(clearance outline)
				(anchor circle)
			)
			(primitives
				(gr_poly
					(pts
						(arc
							(start -0.254 -0.1016)
							(mid -0.3556 0)
							(end -0.254 0.1016)
						)
						(xy 0.3556 0.1016) (xy 0.3556 -0.1016)
					)
					(width 0)
					(fill yes)
				)
			)
		)
		(pad "26" smd custom
			(at -2.4511 -0.199898 90)
			(size 0.0508 0.0508)
			(layers "B.Cu" "B.Mask" "B.Paste")
			(net "GND")
			(options
				(clearance outline)
				(anchor circle)
			)
			(primitives
				(gr_poly
					(pts
						(arc
							(start -0.254 -0.1016)
							(mid -0.3556 0)
							(end -0.254 0.1016)
						)
						(xy 0.3556 0.1016) (xy 0.3556 -0.1016)
					)
					(width 0)
					(fill yes)
				)
			)
		)
		(pad "27" smd custom
			(at -2.4511 -0.599948 90)
			(size 0.0508 0.0508)
			(layers "B.Cu" "B.Mask" "B.Paste")
			(net "GND")
			(options
				(clearance outline)
				(anchor circle)
			)
			(primitives
				(gr_poly
					(pts
						(arc
							(start -0.254 -0.1016)
							(mid -0.3556 0)
							(end -0.254 0.1016)
						)
						(xy 0.3556 0.1016) (xy 0.3556 -0.1016)
					)
					(width 0)
					(fill yes)
				)
			)
		)
		(pad "28" smd custom
			(at -2.4511 -0.999998 90)
			(size 0.0508 0.0508)
			(layers "B.Cu" "B.Mask" "B.Paste")
			(net "Net_335")
			(options
				(clearance outline)
				(anchor circle)
			)
			(primitives
				(gr_poly
					(pts
						(arc
							(start -0.254 -0.1016)
							(mid -0.3556 0)
							(end -0.254 0.1016)
						)
						(xy 0.3556 0.1016) (xy 0.3556 -0.1016)
					)
					(width 0)
					(fill yes)
				)
			)
		)
		(pad "29" smd custom
			(at -2.4511 -1.400048 90)
			(size 0.0508 0.0508)
			(layers "B.Cu" "B.Mask" "B.Paste")
			(net "Net_254")
			(options
				(clearance outline)
				(anchor circle)
			)
			(primitives
				(gr_poly
					(pts
						(arc
							(start -0.254 -0.1016)
							(mid -0.3556 0)
							(end -0.254 0.1016)
						)
						(xy 0.3556 0.1016) (xy 0.3556 -0.1016)
					)
					(width 0)
					(fill yes)
				)
			)
		)
		(pad "30" smd custom
			(at -2.4511 -1.800098 90)
			(size 0.0508 0.0508)
			(layers "B.Cu" "B.Mask" "B.Paste")
			(net "Net_253")
			(options
				(clearance outline)
				(anchor circle)
			)
			(primitives
				(gr_poly
					(pts
						(arc
							(start -0.254 -0.1016)
							(mid -0.3556 0)
							(end -0.254 0.1016)
						)
						(xy 0.3556 0.1016) (xy 0.3556 -0.1016)
					)
					(width 0)
					(fill yes)
				)
			)
		)
		(pad "31" smd custom
			(at -1.800098 -2.4511 90)
			(size 0.0508 0.0508)
			(layers "B.Cu" "B.Mask" "B.Paste")
			(net "Net_301")
			(options
				(clearance outline)
				(anchor circle)
			)
			(primitives
				(gr_poly
					(pts
						(arc
							(start 0.1016 -0.254)
							(mid 0 -0.3556)
							(end -0.1016 -0.254)
						)
						(xy -0.1016 0.3556) (xy 0.1016 0.3556)
					)
					(width 0)
					(fill yes)
				)
			)
		)
		(pad "32" smd custom
			(at -1.400048 -2.4511 90)
			(size 0.0508 0.0508)
			(layers "B.Cu" "B.Mask" "B.Paste")
			(net "PU_VR_PVCCIO_CPU0_FAULT1")
			(options
				(clearance outline)
				(anchor circle)
			)
			(primitives
				(gr_poly
					(pts
						(arc
							(start 0.1016 -0.254)
							(mid 0 -0.3556)
							(end -0.1016 -0.254)
						)
						(xy -0.1016 0.3556) (xy 0.1016 0.3556)
					)
					(width 0)
					(fill yes)
				)
			)
		)
		(pad "33" smd custom
			(at -0.999998 -2.4511 90)
			(size 0.0508 0.0508)
			(layers "B.Cu" "B.Mask" "B.Paste")
			(net "VR_PVCCIO_CPU0_XADDR2")
			(options
				(clearance outline)
				(anchor circle)
			)
			(primitives
				(gr_poly
					(pts
						(arc
							(start 0.1016 -0.254)
							(mid 0 -0.3556)
							(end -0.1016 -0.254)
						)
						(xy -0.1016 0.3556) (xy 0.1016 0.3556)
					)
					(width 0)
					(fill yes)
				)
			)
		)
		(pad "34" smd custom
			(at -0.599948 -2.4511 90)
			(size 0.0508 0.0508)
			(layers "B.Cu" "B.Mask" "B.Paste")
			(net "Net_252")
			(options
				(clearance outline)
				(anchor circle)
			)
			(primitives
				(gr_poly
					(pts
						(arc
							(start 0.1016 -0.254)
							(mid 0 -0.3556)
							(end -0.1016 -0.254)
						)
						(xy -0.1016 0.3556) (xy 0.1016 0.3556)
					)
					(width 0)
					(fill yes)
				)
			)
		)
		(pad "35" smd custom
			(at -0.199898 -2.4511 90)
			(size 0.0508 0.0508)
			(layers "B.Cu" "B.Mask" "B.Paste")
			(net "A_TSENSE_PVCCIO_CPU0")
			(options
				(clearance outline)
				(anchor circle)
			)
			(primitives
				(gr_poly
					(pts
						(arc
							(start 0.1016 -0.254)
							(mid 0 -0.3556)
							(end -0.1016 -0.254)
						)
						(xy -0.1016 0.3556) (xy 0.1016 0.3556)
					)
					(width 0)
					(fill yes)
				)
			)
		)
		(pad "36" smd custom
			(at 0.199898 -2.4511 90)
			(size 0.0508 0.0508)
			(layers "B.Cu" "B.Mask" "B.Paste")
			(net "VR_PVCCIO_CPU0_XADDR1")
			(options
				(clearance outline)
				(anchor circle)
			)
			(primitives
				(gr_poly
					(pts
						(arc
							(start 0.1016 -0.254)
							(mid 0 -0.3556)
							(end -0.1016 -0.254)
						)
						(xy -0.1016 0.3556) (xy 0.1016 0.3556)
					)
					(width 0)
					(fill yes)
				)
			)
		)
		(pad "37" smd custom
			(at 0.599948 -2.4511 90)
			(size 0.0508 0.0508)
			(layers "B.Cu" "B.Mask" "B.Paste")
			(net "VR_PVCCIO_CPU0_VINSEN")
			(options
				(clearance outline)
				(anchor circle)
			)
			(primitives
				(gr_poly
					(pts
						(arc
							(start 0.1016 -0.254)
							(mid 0 -0.3556)
							(end -0.1016 -0.254)
						)
						(xy -0.1016 0.3556) (xy 0.1016 0.3556)
					)
					(width 0)
					(fill yes)
				)
			)
		)
		(pad "38" smd custom
			(at 0.999998 -2.4511 90)
			(size 0.0508 0.0508)
			(layers "B.Cu" "B.Mask" "B.Paste")
			(net "Net_265")
			(options
				(clearance outline)
				(anchor circle)
			)
			(primitives
				(gr_poly
					(pts
						(arc
							(start 0.1016 -0.254)
							(mid 0 -0.3556)
							(end -0.1016 -0.254)
						)
						(xy -0.1016 0.3556) (xy 0.1016 0.3556)
					)
					(width 0)
					(fill yes)
				)
			)
		)
		(pad "39" smd custom
			(at 1.400048 -2.4511 90)
			(size 0.0508 0.0508)
			(layers "B.Cu" "B.Mask" "B.Paste")
			(net "VR_PVCCIO_CPU0_VDD")
			(options
				(clearance outline)
				(anchor circle)
			)
			(primitives
				(gr_poly
					(pts
						(arc
							(start 0.1016 -0.254)
							(mid 0 -0.3556)
							(end -0.1016 -0.254)
						)
						(xy -0.1016 0.3556) (xy 0.1016 0.3556)
					)
					(width 0)
					(fill yes)
				)
			)
		)
		(pad "40" smd custom
			(at 1.800098 -2.4511 90)
			(size 0.0508 0.0508)
			(layers "B.Cu" "B.Mask" "B.Paste")
			(net "VR_PVCCIO_CPU0_VD12")
			(options
				(clearance outline)
				(anchor circle)
			)
			(primitives
				(gr_poly
					(pts
						(arc
							(start 0.1016 -0.254)
							(mid 0 -0.3556)
							(end -0.1016 -0.254)
						)
						(xy -0.1016 0.3556) (xy 0.1016 0.3556)
					)
					(width 0)
					(fill yes)
				)
			)
		)
		(pad "41" smd rect
			(at 0 0 90)
			(size 3.683 3.683)
			(layers "B.Cu" "B.Mask" "B.Paste")
			(net "GND")
		)
	)
)
